(kicad_pcb
	(version 20260206)
	(generator "pcbnew")
	(generator_version "10.0")
	(general
		(thickness 1.6)
		(legacy_teardrops no)
	)
	(paper "A4")
	(title_block
		(title "12092022_DA0F0TMDCD0_F0T_Management_Board_D_brd_V3_OCP.brd")
		(comment 1 "Grand Teton / footprints 442-448 of 1440")
	)
	(layers
		(0 "F.Cu" signal "TOP")
		(4 "In1.Cu" signal "GND")
		(6 "In2.Cu" signal "IN1")
		(8 "In3.Cu" signal "GND1")
		(10 "In4.Cu" signal "IN2")
		(12 "In5.Cu" signal "VCC")
		(14 "In6.Cu" signal "VCC1")
		(16 "In7.Cu" signal "IN3")
		(18 "In8.Cu" signal "GND2")
		(20 "In9.Cu" signal "IN4")
		(22 "In10.Cu" signal "GND3")
		(2 "B.Cu" signal "BOTTOM")
		(9 "F.Adhes" user "F.Adhesive")
		(11 "B.Adhes" user "B.Adhesive")
		(13 "F.Paste" user "Package Geometry/Pastemask Top")
		(15 "B.Paste" user "Package Geometry/Pastemask Bottom")
		(5 "F.SilkS" user "Ref Des/Silkscreen Top")
		(7 "B.SilkS" user "Ref Des/Silkscreen Bottom")
		(1 "F.Mask" user "Board Geometry/Soldermask Top")
		(3 "B.Mask" user "Board Geometry/Soldermask Bottom")
		(17 "Dwgs.User" user "User.Drawings")
		(19 "Cmts.User" user "User.Comments")
		(21 "Eco1.User" user "User.Eco1")
		(23 "Eco2.User" user "User.Eco2")
		(25 "Edge.Cuts" user "Board Geometry/Outline")
		(27 "Margin" user)
		(31 "F.CrtYd" user "Package Geometry/Place Bound Top")
		(29 "B.CrtYd" user "Package Geometry/Place Bound Bottom")
		(35 "F.Fab" user "Ref Des/Assembly Top")
		(33 "B.Fab" user "Ref Des/Assembly Bottom")
	)
	(footprint ""
		(layer "F.Cu")
		(at 13.22197 -31.800292 -90)
		(property "Reference" "PC212"
			(at 0 0 270)
			(layer "F.SilkS")
			(hide yes)
			(effects
				(font
					(size 1.27 1.27)
				)
			)
		)
		(property "Value" ""
			(at 0 0 270)
			(layer "F.Fab")
			(effects
				(font
					(size 1.27 1.27)
				)
			)
		)
		(duplicate_pad_numbers_are_jumpers no)
		(fp_line
			(start -0.7874 0.4064)
			(end -0.7874 -0.4064)
			(stroke
				(width 0.1524)
				(type default)
			)
			(layer "F.SilkS")
		)
		(fp_line
			(start 0.7874 0.4064)
			(end -0.7874 0.4064)
			(stroke
				(width 0.1524)
				(type default)
			)
			(layer "F.SilkS")
		)
		(fp_line
			(start -0.7874 -0.4064)
			(end 0.7874 -0.4064)
			(stroke
				(width 0.1524)
				(type default)
			)
			(layer "F.SilkS")
		)
		(fp_line
			(start 0.7874 -0.4064)
			(end 0.7874 0.4064)
			(stroke
				(width 0.1524)
				(type default)
			)
			(layer "F.SilkS")
		)
		(fp_line
			(start -0.67945 0.3048)
			(end -0.67945 -0.305054)
			(stroke
				(width 0.1)
				(type default)
			)
			(layer "F.Fab")
		)
		(fp_line
			(start -0.12065 0.3048)
			(end -0.67945 0.3048)
			(stroke
				(width 0.1)
				(type default)
			)
			(layer "F.Fab")
		)
		(fp_line
			(start 0.120396 0.3048)
			(end 0.120396 0.2794)
			(stroke
				(width 0.1)
				(type default)
			)
			(layer "F.Fab")
		)
		(fp_line
			(start 0.67945 0.3048)
			(end 0.120396 0.3048)
			(stroke
				(width 0.1)
				(type default)
			)
			(layer "F.Fab")
		)
		(fp_line
			(start -0.12065 0.2794)
			(end -0.12065 0.3048)
			(stroke
				(width 0.1)
				(type default)
			)
			(layer "F.Fab")
		)
		(fp_line
			(start 0.120396 0.2794)
			(end -0.12065 0.2794)
			(stroke
				(width 0.1)
				(type default)
			)
			(layer "F.Fab")
		)
		(fp_line
			(start -0.12065 -0.2794)
			(end 0.12065 -0.2794)
			(stroke
				(width 0.1)
				(type default)
			)
			(layer "F.Fab")
		)
		(fp_line
			(start 0.12065 -0.2794)
			(end 0.12065 -0.3048)
			(stroke
				(width 0.1)
				(type default)
			)
			(layer "F.Fab")
		)
		(fp_line
			(start 0.12065 -0.3048)
			(end 0.67945 -0.3048)
			(stroke
				(width 0.1)
				(type default)
			)
			(layer "F.Fab")
		)
		(fp_line
			(start 0.67945 -0.3048)
			(end 0.67945 0.3048)
			(stroke
				(width 0.1)
				(type default)
			)
			(layer "F.Fab")
		)
		(fp_line
			(start -0.67945 -0.305054)
			(end -0.12065 -0.305054)
			(stroke
				(width 0.1)
				(type default)
			)
			(layer "F.Fab")
		)
		(fp_line
			(start -0.12065 -0.305054)
			(end -0.12065 -0.2794)
			(stroke
				(width 0.1)
				(type default)
			)
			(layer "F.Fab")
		)
		(pad "1" smd circle
			(at -0.40005 0 270)
			(size 0 0)
			(layers "F.Cu" "F.Mask" "F.Paste")
			(net "P5V_AUX")
		)
		(pad "2" smd circle
			(at 0.40005 0 270)
			(size 0 0)
			(layers "F.Cu" "F.Mask" "F.Paste")
			(net "GND")
		)
	)
	(footprint ""
		(layer "F.Cu")
		(at 65.056512 -63.926466 -90)
		(property "Reference" "R643"
			(at 0 0 270)
			(layer "F.SilkS")
			(hide yes)
			(effects
				(font
					(size 1.27 1.27)
				)
			)
		)
		(property "Value" ""
			(at 0 0 270)
			(layer "F.Fab")
			(effects
				(font
					(size 1.27 1.27)
				)
			)
		)
		(duplicate_pad_numbers_are_jumpers no)
		(fp_line
			(start -0.7874 0.4064)
			(end -0.7874 -0.4064)
			(stroke
				(width 0.1524)
				(type default)
			)
			(layer "F.SilkS")
		)
		(fp_line
			(start 0.7874 0.4064)
			(end -0.7874 0.4064)
			(stroke
				(width 0.1524)
				(type default)
			)
			(layer "F.SilkS")
		)
		(fp_line
			(start -0.7874 -0.4064)
			(end 0.7874 -0.4064)
			(stroke
				(width 0.1524)
				(type default)
			)
			(layer "F.SilkS")
		)
		(fp_line
			(start 0.7874 -0.4064)
			(end 0.7874 0.4064)
			(stroke
				(width 0.1524)
				(type default)
			)
			(layer "F.SilkS")
		)
		(fp_line
			(start -0.67945 0.3048)
			(end -0.67945 -0.305054)
			(stroke
				(width 0.1)
				(type default)
			)
			(layer "F.Fab")
		)
		(fp_line
			(start -0.12065 0.3048)
			(end -0.67945 0.3048)
			(stroke
				(width 0.1)
				(type default)
			)
			(layer "F.Fab")
		)
		(fp_line
			(start 0.120396 0.3048)
			(end 0.120396 0.2794)
			(stroke
				(width 0.1)
				(type default)
			)
			(layer "F.Fab")
		)
		(fp_line
			(start 0.67945 0.3048)
			(end 0.120396 0.3048)
			(stroke
				(width 0.1)
				(type default)
			)
			(layer "F.Fab")
		)
		(fp_line
			(start -0.12065 0.2794)
			(end -0.12065 0.3048)
			(stroke
				(width 0.1)
				(type default)
			)
			(layer "F.Fab")
		)
		(fp_line
			(start 0.120396 0.2794)
			(end -0.12065 0.2794)
			(stroke
				(width 0.1)
				(type default)
			)
			(layer "F.Fab")
		)
		(fp_line
			(start -0.12065 -0.2794)
			(end 0.12065 -0.2794)
			(stroke
				(width 0.1)
				(type default)
			)
			(layer "F.Fab")
		)
		(fp_line
			(start 0.12065 -0.2794)
			(end 0.12065 -0.3048)
			(stroke
				(width 0.1)
				(type default)
			)
			(layer "F.Fab")
		)
		(fp_line
			(start 0.12065 -0.3048)
			(end 0.67945 -0.3048)
			(stroke
				(width 0.1)
				(type default)
			)
			(layer "F.Fab")
		)
		(fp_line
			(start 0.67945 -0.3048)
			(end 0.67945 0.3048)
			(stroke
				(width 0.1)
				(type default)
			)
			(layer "F.Fab")
		)
		(fp_line
			(start -0.67945 -0.305054)
			(end -0.12065 -0.305054)
			(stroke
				(width 0.1)
				(type default)
			)
			(layer "F.Fab")
		)
		(fp_line
			(start -0.12065 -0.305054)
			(end -0.12065 -0.2794)
			(stroke
				(width 0.1)
				(type default)
			)
			(layer "F.Fab")
		)
		(pad "1" smd circle
			(at -0.40005 0 270)
			(size 0 0)
			(layers "F.Cu" "F.Mask" "F.Paste")
			(net "PWRGD_DSW_PWROK")
		)
		(pad "2" smd circle
			(at 0.40005 0 270)
			(size 0 0)
			(layers "F.Cu" "F.Mask" "F.Paste")
			(net "PWRGD_DSW_PWROK_R1")
		)
	)
	(footprint ""
		(layer "F.Cu")
		(at 40.821102 -65.793366 90)
		(property "Reference" "R198"
			(at 0 0 90)
			(layer "F.SilkS")
			(hide yes)
			(effects
				(font
					(size 1.27 1.27)
				)
			)
		)
		(property "Value" ""
			(at 0 0 90)
			(layer "F.Fab")
			(effects
				(font
					(size 1.27 1.27)
				)
			)
		)
		(duplicate_pad_numbers_are_jumpers no)
		(fp_line
			(start 0.7874 -0.4064)
			(end 0.7874 0.4064)
			(stroke
				(width 0.1524)
				(type default)
			)
			(layer "F.SilkS")
		)
		(fp_line
			(start -0.7874 -0.4064)
			(end 0.7874 -0.4064)
			(stroke
				(width 0.1524)
				(type default)
			)
			(layer "F.SilkS")
		)
		(fp_line
			(start 0.7874 0.4064)
			(end -0.7874 0.4064)
			(stroke
				(width 0.1524)
				(type default)
			)
			(layer "F.SilkS")
		)
		(fp_line
			(start -0.7874 0.4064)
			(end -0.7874 -0.4064)
			(stroke
				(width 0.1524)
				(type default)
			)
			(layer "F.SilkS")
		)
		(fp_line
			(start -0.12065 -0.305054)
			(end -0.12065 -0.2794)
			(stroke
				(width 0.1)
				(type default)
			)
			(layer "F.Fab")
		)
		(fp_line
			(start -0.67945 -0.305054)
			(end -0.12065 -0.305054)
			(stroke
				(width 0.1)
				(type default)
			)
			(layer "F.Fab")
		)
		(fp_line
			(start 0.67945 -0.3048)
			(end 0.67945 0.3048)
			(stroke
				(width 0.1)
				(type default)
			)
			(layer "F.Fab")
		)
		(fp_line
			(start 0.12065 -0.3048)
			(end 0.67945 -0.3048)
			(stroke
				(width 0.1)
				(type default)
			)
			(layer "F.Fab")
		)
		(fp_line
			(start 0.12065 -0.2794)
			(end 0.12065 -0.3048)
			(stroke
				(width 0.1)
				(type default)
			)
			(layer "F.Fab")
		)
		(fp_line
			(start -0.12065 -0.2794)
			(end 0.12065 -0.2794)
			(stroke
				(width 0.1)
				(type default)
			)
			(layer "F.Fab")
		)
		(fp_line
			(start 0.120396 0.2794)
			(end -0.12065 0.2794)
			(stroke
				(width 0.1)
				(type default)
			)
			(layer "F.Fab")
		)
		(fp_line
			(start -0.12065 0.2794)
			(end -0.12065 0.3048)
			(stroke
				(width 0.1)
				(type default)
			)
			(layer "F.Fab")
		)
		(fp_line
			(start 0.67945 0.3048)
			(end 0.120396 0.3048)
			(stroke
				(width 0.1)
				(type default)
			)
			(layer "F.Fab")
		)
		(fp_line
			(start 0.120396 0.3048)
			(end 0.120396 0.2794)
			(stroke
				(width 0.1)
				(type default)
			)
			(layer "F.Fab")
		)
		(fp_line
			(start -0.12065 0.3048)
			(end -0.67945 0.3048)
			(stroke
				(width 0.1)
				(type default)
			)
			(layer "F.Fab")
		)
		(fp_line
			(start -0.67945 0.3048)
			(end -0.67945 -0.305054)
			(stroke
				(width 0.1)
				(type default)
			)
			(layer "F.Fab")
		)
		(pad "1" smd circle
			(at -0.40005 0 90)
			(size 0 0)
			(layers "F.Cu" "F.Mask" "F.Paste")
			(net "I3C3_SCL_R")
		)
		(pad "2" smd circle
			(at 0.40005 0 90)
			(size 0 0)
			(layers "F.Cu" "F.Mask" "F.Paste")
			(net "I3C3_SPD_SCL")
		)
	)
	(footprint ""
		(layer "F.Cu")
		(at 36.322 -106.934 -90)
		(property "Reference" "R481"
			(at 0 0 270)
			(layer "F.SilkS")
			(hide yes)
			(effects
				(font
					(size 1.27 1.27)
				)
			)
		)
		(property "Value" ""
			(at 0 0 270)
			(layer "F.Fab")
			(effects
				(font
					(size 1.27 1.27)
				)
			)
		)
		(duplicate_pad_numbers_are_jumpers no)
		(fp_line
			(start -0.7874 0.4064)
			(end -0.7874 -0.4064)
			(stroke
				(width 0.1524)
				(type default)
			)
			(layer "F.SilkS")
		)
		(fp_line
			(start 0.7874 0.4064)
			(end -0.7874 0.4064)
			(stroke
				(width 0.1524)
				(type default)
			)
			(layer "F.SilkS")
		)
		(fp_line
			(start -0.7874 -0.4064)
			(end 0.7874 -0.4064)
			(stroke
				(width 0.1524)
				(type default)
			)
			(layer "F.SilkS")
		)
		(fp_line
			(start 0.7874 -0.4064)
			(end 0.7874 0.4064)
			(stroke
				(width 0.1524)
				(type default)
			)
			(layer "F.SilkS")
		)
		(fp_line
			(start -0.67945 0.3048)
			(end -0.67945 -0.305054)
			(stroke
				(width 0.1)
				(type default)
			)
			(layer "F.Fab")
		)
		(fp_line
			(start -0.12065 0.3048)
			(end -0.67945 0.3048)
			(stroke
				(width 0.1)
				(type default)
			)
			(layer "F.Fab")
		)
		(fp_line
			(start 0.120396 0.3048)
			(end 0.120396 0.2794)
			(stroke
				(width 0.1)
				(type default)
			)
			(layer "F.Fab")
		)
		(fp_line
			(start 0.67945 0.3048)
			(end 0.120396 0.3048)
			(stroke
				(width 0.1)
				(type default)
			)
			(layer "F.Fab")
		)
		(fp_line
			(start -0.12065 0.2794)
			(end -0.12065 0.3048)
			(stroke
				(width 0.1)
				(type default)
			)
			(layer "F.Fab")
		)
		(fp_line
			(start 0.120396 0.2794)
			(end -0.12065 0.2794)
			(stroke
				(width 0.1)
				(type default)
			)
			(layer "F.Fab")
		)
		(fp_line
			(start -0.12065 -0.2794)
			(end 0.12065 -0.2794)
			(stroke
				(width 0.1)
				(type default)
			)
			(layer "F.Fab")
		)
		(fp_line
			(start 0.12065 -0.2794)
			(end 0.12065 -0.3048)
			(stroke
				(width 0.1)
				(type default)
			)
			(layer "F.Fab")
		)
		(fp_line
			(start 0.12065 -0.3048)
			(end 0.67945 -0.3048)
			(stroke
				(width 0.1)
				(type default)
			)
			(layer "F.Fab")
		)
		(fp_line
			(start 0.67945 -0.3048)
			(end 0.67945 0.3048)
			(stroke
				(width 0.1)
				(type default)
			)
			(layer "F.Fab")
		)
		(fp_line
			(start -0.67945 -0.305054)
			(end -0.12065 -0.305054)
			(stroke
				(width 0.1)
				(type default)
			)
			(layer "F.Fab")
		)
		(fp_line
			(start -0.12065 -0.305054)
			(end -0.12065 -0.2794)
			(stroke
				(width 0.1)
				(type default)
			)
			(layer "F.Fab")
		)
		(pad "1" smd circle
			(at -0.40005 0 270)
			(size 0 0)
			(layers "F.Cu" "F.Mask" "F.Paste")
			(net "SPI_PCH_MUXED_CLK")
		)
		(pad "2" smd circle
			(at 0.40005 0 270)
			(size 0 0)
			(layers "F.Cu" "F.Mask" "F.Paste")
			(net "SPI_PCH_CLK_FLASH_R1")
		)
	)
	(footprint ""
		(layer "F.Cu")
		(at 82.44967 -65.20815 -90)
		(property "Reference" "PL31"
			(at 0 0 270)
			(layer "F.SilkS")
			(hide yes)
			(effects
				(font
					(size 1.27 1.27)
				)
			)
		)
		(property "Value" ""
			(at 0 0 270)
			(layer "F.Fab")
			(effects
				(font
					(size 1.27 1.27)
				)
			)
		)
		(duplicate_pad_numbers_are_jumpers no)
		(fp_line
			(start -3.64998 3.350006)
			(end -3.64998 1.8288)
			(stroke
				(width 0.1524)
				(type default)
			)
			(layer "F.SilkS")
		)
		(fp_line
			(start 3.64998 3.350006)
			(end -3.64998 3.350006)
			(stroke
				(width 0.1524)
				(type default)
			)
			(layer "F.SilkS")
		)
		(fp_line
			(start 3.64998 1.8034)
			(end 3.64998 3.350006)
			(stroke
				(width 0.1524)
				(type default)
			)
			(layer "F.SilkS")
		)
		(fp_line
			(start -3.64998 -1.8034)
			(end -3.64998 -3.350006)
			(stroke
				(width 0.1524)
				(type default)
			)
			(layer "F.SilkS")
		)
		(fp_line
			(start -3.6576 -3.350006)
			(end 3.64998 -3.350006)
			(stroke
				(width 0.1524)
				(type default)
			)
			(layer "F.SilkS")
		)
		(fp_line
			(start 3.64998 -3.350006)
			(end 3.64998 -1.8034)
			(stroke
				(width 0.1524)
				(type default)
			)
			(layer "F.SilkS")
		)
		(fp_line
			(start -3.64998 3.350006)
			(end -3.64998 -3.350006)
			(stroke
				(width 0.1)
				(type default)
			)
			(layer "F.Fab")
		)
		(fp_line
			(start 3.64998 3.350006)
			(end -3.64998 3.350006)
			(stroke
				(width 0.1)
				(type default)
			)
			(layer "F.Fab")
		)
		(fp_line
			(start -3.64998 -3.350006)
			(end 3.64998 -3.350006)
			(stroke
				(width 0.1)
				(type default)
			)
			(layer "F.Fab")
		)
		(fp_line
			(start 3.64998 -3.350006)
			(end 3.64998 3.350006)
			(stroke
				(width 0.1)
				(type default)
			)
			(layer "F.Fab")
		)
		(pad "1" smd rect
			(at -2.92481 0 270)
			(size 2.15392 3.302)
			(layers "F.Cu" "F.Mask" "F.Paste")
			(net "SW_P1V2_AUX_SW")
		)
		(pad "2" smd rect
			(at 2.92481 0 270)
			(size 2.15392 3.302)
			(layers "F.Cu" "F.Mask" "F.Paste")
			(net "P1V2_AUX")
		)
	)
	(footprint ""
		(layer "F.Cu")
		(at -4.191 -138.303)
		(property "Reference" "DM3"
			(at -0.3937 -0.588518 0)
			(unlocked yes)
			(layer "F.SilkS")
			(effects
				(font
					(size 0.254 0.127)
					(thickness 0.000001)
				)
				(justify left)
			)
		)
		(property "Value" ""
			(at 0 0 0)
			(layer "F.Fab")
			(effects
				(font
					(size 1.27 1.27)
				)
			)
		)
		(duplicate_pad_numbers_are_jumpers no)
		(pad "1" smd circle
			(at 0 0)
			(size 0.762 0.762)
			(layers "F.Cu" "F.Mask" "F.Paste")
			(net "Net_1198")
		)
	)
	(footprint ""
		(layer "F.Cu")
		(at 28.575 -102.743 -90)
		(property "Reference" "R577"
			(at 0 0 270)
			(layer "F.SilkS")
			(hide yes)
			(effects
				(font
					(size 1.27 1.27)
				)
			)
		)
		(property "Value" ""
			(at 0 0 270)
			(layer "F.Fab")
			(effects
				(font
					(size 1.27 1.27)
				)
			)
		)
		(duplicate_pad_numbers_are_jumpers no)
		(fp_line
			(start -0.7874 0.4064)
			(end -0.7874 -0.4064)
			(stroke
				(width 0.1524)
				(type default)
			)
			(layer "F.SilkS")
		)
		(fp_line
			(start 0.7874 0.4064)
			(end -0.7874 0.4064)
			(stroke
				(width 0.1524)
				(type default)
			)
			(layer "F.SilkS")
		)
		(fp_line
			(start -0.7874 -0.4064)
			(end 0.7874 -0.4064)
			(stroke
				(width 0.1524)
				(type default)
			)
			(layer "F.SilkS")
		)
		(fp_line
			(start 0.7874 -0.4064)
			(end 0.7874 0.4064)
			(stroke
				(width 0.1524)
				(type default)
			)
			(layer "F.SilkS")
		)
		(fp_line
			(start -0.67945 0.3048)
			(end -0.67945 -0.305054)
			(stroke
				(width 0.1)
				(type default)
			)
			(layer "F.Fab")
		)
		(fp_line
			(start -0.12065 0.3048)
			(end -0.67945 0.3048)
			(stroke
				(width 0.1)
				(type default)
			)
			(layer "F.Fab")
		)
		(fp_line
			(start 0.120396 0.3048)
			(end 0.120396 0.2794)
			(stroke
				(width 0.1)
				(type default)
			)
			(layer "F.Fab")
		)
		(fp_line
			(start 0.67945 0.3048)
			(end 0.120396 0.3048)
			(stroke
				(width 0.1)
				(type default)
			)
			(layer "F.Fab")
		)
		(fp_line
			(start -0.12065 0.2794)
			(end -0.12065 0.3048)
			(stroke
				(width 0.1)
				(type default)
			)
			(layer "F.Fab")
		)
		(fp_line
			(start 0.120396 0.2794)
			(end -0.12065 0.2794)
			(stroke
				(width 0.1)
				(type default)
			)
			(layer "F.Fab")
		)
		(fp_line
			(start -0.12065 -0.2794)
			(end 0.12065 -0.2794)
			(stroke
				(width 0.1)
				(type default)
			)
			(layer "F.Fab")
		)
		(fp_line
			(start 0.12065 -0.2794)
			(end 0.12065 -0.3048)
			(stroke
				(width 0.1)
				(type default)
			)
			(layer "F.Fab")
		)
		(fp_line
			(start 0.12065 -0.3048)
			(end 0.67945 -0.3048)
			(stroke
				(width 0.1)
				(type default)
			)
			(layer "F.Fab")
		)
		(fp_line
			(start 0.67945 -0.3048)
			(end 0.67945 0.3048)
			(stroke
				(width 0.1)
				(type default)
			)
			(layer "F.Fab")
		)
		(fp_line
			(start -0.67945 -0.305054)
			(end -0.12065 -0.305054)
			(stroke
				(width 0.1)
				(type default)
			)
			(layer "F.Fab")
		)
		(fp_line
			(start -0.12065 -0.305054)
			(end -0.12065 -0.2794)
			(stroke
				(width 0.1)
				(type default)
			)
			(layer "F.Fab")
		)
		(pad "1" smd circle
			(at -0.40005 0 270)
			(size 0 0)
			(layers "F.Cu" "F.Mask" "F.Paste")
			(net "FM_SOL_UART_CH_SEL")
		)
		(pad "2" smd circle
			(at 0.40005 0 270)
			(size 0 0)
			(layers "F.Cu" "F.Mask" "F.Paste")
			(net "FM_SOL_UART_CH_SEL_R2")
		)
	)
)
